#ISCELL
  logical_power design_note *
  *
#ISCELL
  mstr_misc dns *
  *
#ISCELL
  pure_quanta quanta_title_block_c *
  *
#ISCELL
  standard offpage *
  page197_i100
#ISCELL
  standard offpage *
  page197_i112
#ISCELL
  standard offpage *
  page197_i113
#ISCELL
  standard offpage *
  page197_i115
#ISCELL
  standard offpage *
  page197_i116
#ISCELL
  standard offpage *
  page197_i119
#ISCELL
  standard offpage *
  page197_i120
#ISCELL
  logical_power universal_power *
  page197_i157
#ISCELL
  logical_power universal_power *
  page197_i158
#ISCELL
  logical_power universal_power *
  page197_i159
#ISCELL
  logical_power universal_power *
  page197_i160
#ISCELL
  logical_power universal_power *
  page197_i161
#ISCELL
  logical_power universal_power *
  page197_i162
#ISCELL
  standard offpage *
  page197_i163
#ISCELL
  standard offpage *
  page197_i164
#ISCELL
  standard offpage *
  page197_i165
#ISCELL
  standard offpage *
  page197_i167
#ISCELL
  standard offpage *
  page197_i168
#ISCELL
  standard offpage *
  page197_i170
#ISCELL
  standard offpage *
  page197_i171
#ISCELL
  standard offpage *
  page197_i172
#CELL
  pure_quanta 9sq440nqqi8 *
  page197_i180
#ISCELL
  standard offpage *
  page197_i182
#ISCELL
  standard offpage *
  page197_i206
#ISCELL
  standard offpage *
  page197_i207
#ISCELL
  standard offpage *
  page197_i242
#CELL
  pure_quanta q_res *
  page197_i252
#ISCELL
  standard offpage *
  page197_i253
#ISCELL
  standard offpage *
  page197_i254
#ISCELL
  standard offpage *
  page197_i255
#ISCELL
  standard offpage *
  page197_i256
#ISCELL
  standard offpage *
  page197_i257
#ISCELL
  standard offpage *
  page197_i258
#ISCELL
  standard offpage *
  page197_i259
#ISCELL
  standard offpage *
  page197_i260
#ISCELL
  standard offpage *
  page197_i261
#ISCELL
  standard offpage *
  page197_i262
#ISCELL
  standard offpage *
  page197_i263
#ISCELL
  standard offpage *
  page197_i264
#CELL
  pure_quanta q_res *
  page197_i265
#CELL
  pure_quanta q_res *
  page197_i267
#CELL
  pure_quanta q_res *
  page197_i268
#CELL
  pure_quanta q_res *
  page197_i269
#CELL
  pure_quanta q_res *
  page197_i270
#CELL
  pure_quanta q_res *
  page197_i271
#CELL
  pure_quanta q_res *
  page197_i272
#CELL
  pure_quanta q_res *
  page197_i273
#CELL
  pure_quanta q_res *
  page197_i274
#CELL
  pure_quanta q_res *
  page197_i275
#CELL
  pure_quanta q_res *
  page197_i276
#CELL
  pure_quanta q_res *
  page197_i277
#CELL
  pure_quanta q_res *
  page197_i278
#ISCELL
  logical_power universal_power *
  page197_i279
#CELL
  pure_quanta q_res *
  page197_i280
#CELL
  pure_quanta q_res *
  page197_i281
#CELL
  pure_quanta q_res *
  page197_i282
#CELL
  pure_quanta q_res *
  page197_i283
#ISCELL
  logical_power universal_gnd *
  page197_i285
#CELL
  pure_quanta q_cap *
  page197_i286
#CELL
  pure_quanta 9sq440nqqi8 *
  page197_i288
#ISCELL
  logical_power universal_gnd *
  page197_i294
#ISCELL
  logical_power universal_gnd *
  page197_i295
#ISCELL
  logical_power universal_gnd *
  page197_i301
#ISCELL
  logical_power universal_gnd *
  page197_i302
#CELL
  pure_quanta q_res *
  page197_i303
#ISCELL
  logical_power universal_power *
  page197_i304
#ISCELL
  standard offpage *
  page197_i330
#CELL
  pure_quanta q_res *
  page197_i378
#CELL
  pure_quanta q_res *
  page197_i379
#CELL
  pure_quanta q_res *
  page197_i380
#CELL
  pure_quanta q_res *
  page197_i381
#CELL
  pure_quanta q_res *
  page197_i382
#CELL
  pure_quanta q_res *
  page197_i383
#ISCELL
  logical_power universal_power *
  page197_i385
#CELL
  pure_quanta q_xtal_4p_13bi_24gnd *
  page197_i391
#CELL
  pure_quanta q_res *
  page197_i392
#CELL
  pure_quanta q_cap *
  page197_i393
#CELL
  pure_quanta q_cap *
  page197_i394
#ISCELL
  standard offpage *
  page197_i99
